# T6G (Grand Teton) — schematic netlist excerpt (pin names and nets, part order shuffled) for the footprints in the layout excerpt that follows; sources: Cadence DE-HDL packaged netlist, KiCad conversion of 04192023_DAF0TMB3IC0_F0TG_MB_C_brd_V02_OCP.brd

R115  Q_RES  1K 1% EMPTY  pkg 0402LF  page 109 : A = P3V3 ; B = PWRGD_CHL_CPU1_DIMM
C340  Q_CAP  0.1UF 10V 10% X7S  pkg C0201  page 334 : A = P0V9_CPU1_RT1_2A ; B = GND
C2462  Q_CAP  22UF 4V 20% X6S  pkg C0402  page 74 : A = PVDDCR_SOC_P1 ; B = GND

(kicad_pcb
	(version 20260206)
	(generator "pcbnew")
	(generator_version "10.0")
	(general
		(thickness 1.6)
		(legacy_teardrops no)
	)
	(paper "A4")
	(title_block
		(title "04192023_DAF0TMB3IC0_F0TG_MB_C_brd_V02_OCP.brd")
		(comment 1 "Grand Teton / footprints 7456-7458 of 8354")
	)
	(layers
		(0 "F.Cu" signal "TOP")
		(4 "In1.Cu" signal "GND")
		(6 "In2.Cu" signal "IN1")
		(8 "In3.Cu" signal "GND1")
		(10 "In4.Cu" signal "IN2")
		(12 "In5.Cu" signal "GND2")
		(14 "In6.Cu" signal "IN3")
		(16 "In7.Cu" signal "GND3")
		(18 "In8.Cu" signal "VCC")
		(20 "In9.Cu" signal "VCC1")
		(22 "In10.Cu" signal "GND4")
		(24 "In11.Cu" signal "IN4")
		(26 "In12.Cu" signal "GND5")
		(28 "In13.Cu" signal "IN5")
		(30 "In14.Cu" signal "GND6")
		(32 "In15.Cu" signal "IN6")
		(34 "In16.Cu" signal "GND7")
		(2 "B.Cu" signal "BOTTOM")
		(9 "F.Adhes" user "F.Adhesive")
		(11 "B.Adhes" user "B.Adhesive")
		(13 "F.Paste" user "Package Geometry/Pastemask Top")
		(15 "B.Paste" user "Package Geometry/Pastemask Bottom")
		(5 "F.SilkS" user "Ref Des/Silkscreen Top")
		(7 "B.SilkS" user "Ref Des/Silkscreen Bottom")
		(1 "F.Mask" user "Board Geometry/Soldermask Top")
		(3 "B.Mask" user "Board Geometry/Soldermask Bottom")
		(17 "Dwgs.User" user "User.Drawings")
		(19 "Cmts.User" user "User.Comments")
		(21 "Eco1.User" user "User.Eco1")
		(23 "Eco2.User" user "User.Eco2")
		(25 "Edge.Cuts" user "Board Geometry/Outline")
		(27 "Margin" user)
		(31 "F.CrtYd" user "Package Geometry/Place Bound Top")
		(29 "B.CrtYd" user "Package Geometry/Place Bound Bottom")
		(35 "F.Fab" user "Ref Des/Assembly Top")
		(33 "B.Fab" user "Ref Des/Assembly Bottom")
	)
	(footprint ""
		(layer "B.Cu")
		(at 202.903836 -193.99631)
		(property "Reference" "R115"
			(at 0 0 0)
			(layer "B.SilkS")
			(hide yes)
			(effects
				(font
					(size 1.27 1.27)
				)
				(justify mirror)
			)
		)
		(property "Value" ""
			(at 0 0 0)
			(layer "B.Fab")
			(effects
				(font
					(size 1.27 1.27)
				)
				(justify mirror)
			)
		)
		(duplicate_pad_numbers_are_jumpers no)
		(fp_line
			(start -0.7874 -0.4064)
			(end -0.7874 0.4064)
			(stroke
				(width 0.1524)
				(type default)
			)
			(layer "B.SilkS")
		)
		(fp_line
			(start -0.7874 0.4064)
			(end 0.7874 0.4064)
			(stroke
				(width 0.1524)
				(type default)
			)
			(layer "B.SilkS")
		)
		(fp_line
			(start 0.7874 -0.4064)
			(end -0.7874 -0.4064)
			(stroke
				(width 0.1524)
				(type default)
			)
			(layer "B.SilkS")
		)
		(fp_line
			(start 0.7874 0.4064)
			(end 0.7874 -0.4064)
			(stroke
				(width 0.1524)
				(type default)
			)
			(layer "B.SilkS")
		)
		(fp_line
			(start -0.67945 -0.3048)
			(end -0.67945 0.3048)
			(stroke
				(width 0.1)
				(type default)
			)
			(layer "B.Fab")
		)
		(fp_line
			(start -0.67945 0.3048)
			(end -0.120396 0.3048)
			(stroke
				(width 0.1)
				(type default)
			)
			(layer "B.Fab")
		)
		(fp_line
			(start -0.12065 -0.3048)
			(end -0.67945 -0.3048)
			(stroke
				(width 0.1)
				(type default)
			)
			(layer "B.Fab")
		)
		(fp_line
			(start -0.12065 -0.2794)
			(end -0.12065 -0.3048)
			(stroke
				(width 0.1)
				(type default)
			)
			(layer "B.Fab")
		)
		(fp_line
			(start -0.120396 0.2794)
			(end 0.12065 0.2794)
			(stroke
				(width 0.1)
				(type default)
			)
			(layer "B.Fab")
		)
		(fp_line
			(start -0.120396 0.3048)
			(end -0.120396 0.2794)
			(stroke
				(width 0.1)
				(type default)
			)
			(layer "B.Fab")
		)
		(fp_line
			(start 0.12065 -0.305054)
			(end 0.12065 -0.2794)
			(stroke
				(width 0.1)
				(type default)
			)
			(layer "B.Fab")
		)
		(fp_line
			(start 0.12065 -0.2794)
			(end -0.12065 -0.2794)
			(stroke
				(width 0.1)
				(type default)
			)
			(layer "B.Fab")
		)
		(fp_line
			(start 0.12065 0.2794)
			(end 0.12065 0.3048)
			(stroke
				(width 0.1)
				(type default)
			)
			(layer "B.Fab")
		)
		(fp_line
			(start 0.12065 0.3048)
			(end 0.67945 0.3048)
			(stroke
				(width 0.1)
				(type default)
			)
			(layer "B.Fab")
		)
		(fp_line
			(start 0.67945 -0.305054)
			(end 0.12065 -0.305054)
			(stroke
				(width 0.1)
				(type default)
			)
			(layer "B.Fab")
		)
		(fp_line
			(start 0.67945 0.3048)
			(end 0.67945 -0.305054)
			(stroke
				(width 0.1)
				(type default)
			)
			(layer "B.Fab")
		)
		(pad "1" smd circle
			(at 0.40005 0 180)
			(size 0 0)
			(layers "B.Cu" "B.Mask" "B.Paste")
			(net "P3V3")
		)
		(pad "2" smd circle
			(at -0.40005 0 180)
			(size 0 0)
			(layers "B.Cu" "B.Mask" "B.Paste")
			(net "PWRGD_CHL_CPU1_DIMM")
		)
	)
	(footprint ""
		(layer "B.Cu")
		(at 96.84639 -388.011162 -90)
		(property "Reference" "C340"
			(at 0 0 90)
			(layer "B.SilkS")
			(hide yes)
			(effects
				(font
					(size 1.27 1.27)
				)
				(justify mirror)
			)
		)
		(property "Value" ""
			(at 0 0 90)
			(layer "B.Fab")
			(effects
				(font
					(size 1.27 1.27)
				)
				(justify mirror)
			)
		)
		(duplicate_pad_numbers_are_jumpers no)
		(fp_line
			(start -0.299974 0.150114)
			(end 0.299974 0.150114)
			(stroke
				(width 0.1)
				(type default)
			)
			(layer "B.Fab")
		)
		(fp_line
			(start 0.299974 0.150114)
			(end 0.299974 -0.150114)
			(stroke
				(width 0.1)
				(type default)
			)
			(layer "B.Fab")
		)
		(fp_line
			(start -0.299974 -0.150114)
			(end -0.299974 0.150114)
			(stroke
				(width 0.1)
				(type default)
			)
			(layer "B.Fab")
		)
		(fp_line
			(start 0.299974 -0.150114)
			(end -0.299974 -0.150114)
			(stroke
				(width 0.1)
				(type default)
			)
			(layer "B.Fab")
		)
		(pad "1" smd rect
			(at 0.2667 0 90)
			(size 0.3048 0.381)
			(layers "B.Cu" "B.Mask" "B.Paste")
			(net "P0V9_CPU1_RT1_2A")
		)
		(pad "2" smd rect
			(at -0.2667 0 90)
			(size 0.3048 0.381)
			(layers "B.Cu" "B.Mask" "B.Paste")
			(net "GND")
		)
	)
	(footprint ""
		(layer "B.Cu")
		(at 125.389386 -259.73024)
		(property "Reference" "C2462"
			(at 0 0 0)
			(layer "B.SilkS")
			(hide yes)
			(effects
				(font
					(size 1.27 1.27)
				)
				(justify mirror)
			)
		)
		(property "Value" ""
			(at 0 0 0)
			(layer "B.Fab")
			(effects
				(font
					(size 1.27 1.27)
				)
				(justify mirror)
			)
		)
		(duplicate_pad_numbers_are_jumpers no)
		(fp_line
			(start -0.7874 -0.4064)
			(end -0.7874 0.4064)
			(stroke
				(width 0.1524)
				(type default)
			)
			(layer "B.SilkS")
		)
		(fp_line
			(start -0.7874 0.4064)
			(end 0.7874 0.4064)
			(stroke
				(width 0.1524)
				(type default)
			)
			(layer "B.SilkS")
		)
		(fp_line
			(start 0.7874 -0.4064)
			(end -0.7874 -0.4064)
			(stroke
				(width 0.1524)
				(type default)
			)
			(layer "B.SilkS")
		)
		(fp_line
			(start 0.7874 0.4064)
			(end 0.7874 -0.4064)
			(stroke
				(width 0.1524)
				(type default)
			)
			(layer "B.SilkS")
		)
		(fp_line
			(start -0.67945 -0.3048)
			(end -0.67945 0.3048)
			(stroke
				(width 0.1)
				(type default)
			)
			(layer "B.Fab")
		)
		(fp_line
			(start -0.67945 0.3048)
			(end -0.120396 0.3048)
			(stroke
				(width 0.1)
				(type default)
			)
			(layer "B.Fab")
		)
		(fp_line
			(start -0.12065 -0.3048)
			(end -0.67945 -0.3048)
			(stroke
				(width 0.1)
				(type default)
			)
			(layer "B.Fab")
		)
		(fp_line
			(start -0.12065 -0.2794)
			(end -0.12065 -0.3048)
			(stroke
				(width 0.1)
				(type default)
			)
			(layer "B.Fab")
		)
		(fp_line
			(start -0.120396 0.2794)
			(end 0.12065 0.2794)
			(stroke
				(width 0.1)
				(type default)
			)
			(layer "B.Fab")
		)
		(fp_line
			(start -0.120396 0.3048)
			(end -0.120396 0.2794)
			(stroke
				(width 0.1)
				(type default)
			)
			(layer "B.Fab")
		)
		(fp_line
			(start 0.12065 -0.305054)
			(end 0.12065 -0.2794)
			(stroke
				(width 0.1)
				(type default)
			)
			(layer "B.Fab")
		)
		(fp_line
			(start 0.12065 -0.2794)
			(end -0.12065 -0.2794)
			(stroke
				(width 0.1)
				(type default)
			)
			(layer "B.Fab")
		)
		(fp_line
			(start 0.12065 0.2794)
			(end 0.12065 0.3048)
			(stroke
				(width 0.1)
				(type default)
			)
			(layer "B.Fab")
		)
		(fp_line
			(start 0.12065 0.3048)
			(end 0.67945 0.3048)
			(stroke
				(width 0.1)
				(type default)
			)
			(layer "B.Fab")
		)
		(fp_line
			(start 0.67945 -0.305054)
			(end 0.12065 -0.305054)
			(stroke
				(width 0.1)
				(type default)
			)
			(layer "B.Fab")
		)
		(fp_line
			(start 0.67945 0.3048)
			(end 0.67945 -0.305054)
			(stroke
				(width 0.1)
				(type default)
			)
			(layer "B.Fab")
		)
		(pad "1" smd circle
			(at 0.40005 0 180)
			(size 0 0)
			(layers "B.Cu" "B.Mask" "B.Paste")
			(net "PVDDCR_SOC_P1")
		)
		(pad "2" smd circle
			(at -0.40005 0 180)
			(size 0 0)
			(layers "B.Cu" "B.Mask" "B.Paste")
			(net "GND")
		)
	)
)
